(kicad_pcb
	(version 20260206)
	(generator "pcbnew")
	(generator_version "10.0")
	(general
		(thickness 1.6)
		(legacy_teardrops no)
	)
	(paper "A4")
	(title_block
		(title "03242023_DA0F0TMBIJ0_F0T_Motherboard_J_brd_V01_OCP.brd")
		(comment 1 "Grand Teton / footprints 2650-2658 of 6105")
	)
	(layers
		(0 "F.Cu" signal "TOP")
		(4 "In1.Cu" signal "GND")
		(6 "In2.Cu" signal "IN1")
		(8 "In3.Cu" signal "GND1")
		(10 "In4.Cu" signal "IN2")
		(12 "In5.Cu" signal "GND2")
		(14 "In6.Cu" signal "IN3")
		(16 "In7.Cu" signal "GND3")
		(18 "In8.Cu" signal "VCC")
		(20 "In9.Cu" signal "VCC1")
		(22 "In10.Cu" signal "GND4")
		(24 "In11.Cu" signal "IN4")
		(26 "In12.Cu" signal "GND5")
		(28 "In13.Cu" signal "IN5")
		(30 "In14.Cu" signal "GND6")
		(32 "In15.Cu" signal "IN6")
		(34 "In16.Cu" signal "GND7")
		(2 "B.Cu" signal "BOTTOM")
		(9 "F.Adhes" user "F.Adhesive")
		(11 "B.Adhes" user "B.Adhesive")
		(13 "F.Paste" user "Package Geometry/Pastemask Top")
		(15 "B.Paste" user "Package Geometry/Pastemask Bottom")
		(5 "F.SilkS" user "Ref Des/Silkscreen Top")
		(7 "B.SilkS" user "Ref Des/Silkscreen Bottom")
		(1 "F.Mask" user "Board Geometry/Soldermask Top")
		(3 "B.Mask" user "Board Geometry/Soldermask Bottom")
		(17 "Dwgs.User" user "User.Drawings")
		(19 "Cmts.User" user "User.Comments")
		(21 "Eco1.User" user "User.Eco1")
		(23 "Eco2.User" user "User.Eco2")
		(25 "Edge.Cuts" user "Board Geometry/Outline")
		(27 "Margin" user)
		(31 "F.CrtYd" user "Package Geometry/Place Bound Top")
		(29 "B.CrtYd" user "Package Geometry/Place Bound Bottom")
		(35 "F.Fab" user "Ref Des/Assembly Top")
		(33 "B.Fab" user "Ref Des/Assembly Bottom")
	)
	(footprint ""
		(layer "F.Cu")
		(at 306.09159 -427.168818 180)
		(property "Reference" "R4265"
			(at 0 0 180)
			(layer "F.SilkS")
			(hide yes)
			(effects
				(font
					(size 1.27 1.27)
				)
			)
		)
		(property "Value" ""
			(at 0 0 180)
			(layer "F.Fab")
			(effects
				(font
					(size 1.27 1.27)
				)
			)
		)
		(duplicate_pad_numbers_are_jumpers no)
		(fp_line
			(start 0.7874 0.4064)
			(end -0.7874 0.4064)
			(stroke
				(width 0.1524)
				(type default)
			)
			(layer "F.SilkS")
		)
		(fp_line
			(start 0.7874 -0.4064)
			(end 0.7874 0.4064)
			(stroke
				(width 0.1524)
				(type default)
			)
			(layer "F.SilkS")
		)
		(fp_line
			(start -0.7874 0.4064)
			(end -0.7874 -0.4064)
			(stroke
				(width 0.1524)
				(type default)
			)
			(layer "F.SilkS")
		)
		(fp_line
			(start -0.7874 -0.4064)
			(end 0.7874 -0.4064)
			(stroke
				(width 0.1524)
				(type default)
			)
			(layer "F.SilkS")
		)
		(fp_line
			(start 0.67945 0.3048)
			(end 0.120396 0.3048)
			(stroke
				(width 0.1)
				(type default)
			)
			(layer "F.Fab")
		)
		(fp_line
			(start 0.67945 -0.3048)
			(end 0.67945 0.3048)
			(stroke
				(width 0.1)
				(type default)
			)
			(layer "F.Fab")
		)
		(fp_line
			(start 0.12065 -0.2794)
			(end 0.12065 -0.3048)
			(stroke
				(width 0.1)
				(type default)
			)
			(layer "F.Fab")
		)
		(fp_line
			(start 0.12065 -0.3048)
			(end 0.67945 -0.3048)
			(stroke
				(width 0.1)
				(type default)
			)
			(layer "F.Fab")
		)
		(fp_line
			(start 0.120396 0.3048)
			(end 0.120396 0.2794)
			(stroke
				(width 0.1)
				(type default)
			)
			(layer "F.Fab")
		)
		(fp_line
			(start 0.120396 0.2794)
			(end -0.12065 0.2794)
			(stroke
				(width 0.1)
				(type default)
			)
			(layer "F.Fab")
		)
		(fp_line
			(start -0.12065 0.3048)
			(end -0.67945 0.3048)
			(stroke
				(width 0.1)
				(type default)
			)
			(layer "F.Fab")
		)
		(fp_line
			(start -0.12065 0.2794)
			(end -0.12065 0.3048)
			(stroke
				(width 0.1)
				(type default)
			)
			(layer "F.Fab")
		)
		(fp_line
			(start -0.12065 -0.2794)
			(end 0.12065 -0.2794)
			(stroke
				(width 0.1)
				(type default)
			)
			(layer "F.Fab")
		)
		(fp_line
			(start -0.12065 -0.305054)
			(end -0.12065 -0.2794)
			(stroke
				(width 0.1)
				(type default)
			)
			(layer "F.Fab")
		)
		(fp_line
			(start -0.67945 0.3048)
			(end -0.67945 -0.305054)
			(stroke
				(width 0.1)
				(type default)
			)
			(layer "F.Fab")
		)
		(fp_line
			(start -0.67945 -0.305054)
			(end -0.12065 -0.305054)
			(stroke
				(width 0.1)
				(type default)
			)
			(layer "F.Fab")
		)
		(pad "1" smd circle
			(at -0.40005 0 180)
			(size 0 0)
			(layers "F.Cu" "F.Mask" "F.Paste")
			(net "PWRGD_P3V3_AUX_PDB_BUF_R")
		)
		(pad "2" smd circle
			(at 0.40005 0 180)
			(size 0 0)
			(layers "F.Cu" "F.Mask" "F.Paste")
			(net "GND")
		)
	)
	(footprint ""
		(layer "F.Cu")
		(at 497.43868 -468.007446)
		(property "Reference" "DM9"
			(at -0.3937 -0.588518 0)
			(unlocked yes)
			(layer "F.SilkS")
			(effects
				(font
					(size 0.254 0.127)
					(thickness 0.000001)
				)
				(justify left)
			)
		)
		(property "Value" ""
			(at 0 0 0)
			(layer "F.Fab")
			(effects
				(font
					(size 1.27 1.27)
				)
			)
		)
		(duplicate_pad_numbers_are_jumpers no)
		(pad "1" smd circle
			(at 0 0)
			(size 0.762 0.762)
			(layers "F.Cu" "F.Mask" "F.Paste")
			(net "Net_8587")
		)
	)
	(footprint ""
		(layer "F.Cu")
		(at 437.515 -94.071948 90)
		(property "Reference" "C2024"
			(at 0 0 90)
			(layer "F.SilkS")
			(hide yes)
			(effects
				(font
					(size 1.27 1.27)
				)
			)
		)
		(property "Value" ""
			(at 0 0 90)
			(layer "F.Fab")
			(effects
				(font
					(size 1.27 1.27)
				)
			)
		)
		(duplicate_pad_numbers_are_jumpers no)
		(fp_line
			(start 0.7874 -0.4064)
			(end 0.7874 0.4064)
			(stroke
				(width 0.1524)
				(type default)
			)
			(layer "F.SilkS")
		)
		(fp_line
			(start -0.7874 -0.4064)
			(end 0.7874 -0.4064)
			(stroke
				(width 0.1524)
				(type default)
			)
			(layer "F.SilkS")
		)
		(fp_line
			(start 0.7874 0.4064)
			(end -0.7874 0.4064)
			(stroke
				(width 0.1524)
				(type default)
			)
			(layer "F.SilkS")
		)
		(fp_line
			(start -0.7874 0.4064)
			(end -0.7874 -0.4064)
			(stroke
				(width 0.1524)
				(type default)
			)
			(layer "F.SilkS")
		)
		(fp_line
			(start -0.12065 -0.305054)
			(end -0.12065 -0.2794)
			(stroke
				(width 0.1)
				(type default)
			)
			(layer "F.Fab")
		)
		(fp_line
			(start -0.67945 -0.305054)
			(end -0.12065 -0.305054)
			(stroke
				(width 0.1)
				(type default)
			)
			(layer "F.Fab")
		)
		(fp_line
			(start 0.67945 -0.3048)
			(end 0.67945 0.3048)
			(stroke
				(width 0.1)
				(type default)
			)
			(layer "F.Fab")
		)
		(fp_line
			(start 0.12065 -0.3048)
			(end 0.67945 -0.3048)
			(stroke
				(width 0.1)
				(type default)
			)
			(layer "F.Fab")
		)
		(fp_line
			(start 0.12065 -0.2794)
			(end 0.12065 -0.3048)
			(stroke
				(width 0.1)
				(type default)
			)
			(layer "F.Fab")
		)
		(fp_line
			(start -0.12065 -0.2794)
			(end 0.12065 -0.2794)
			(stroke
				(width 0.1)
				(type default)
			)
			(layer "F.Fab")
		)
		(fp_line
			(start 0.120396 0.2794)
			(end -0.12065 0.2794)
			(stroke
				(width 0.1)
				(type default)
			)
			(layer "F.Fab")
		)
		(fp_line
			(start -0.12065 0.2794)
			(end -0.12065 0.3048)
			(stroke
				(width 0.1)
				(type default)
			)
			(layer "F.Fab")
		)
		(fp_line
			(start 0.67945 0.3048)
			(end 0.120396 0.3048)
			(stroke
				(width 0.1)
				(type default)
			)
			(layer "F.Fab")
		)
		(fp_line
			(start 0.120396 0.3048)
			(end 0.120396 0.2794)
			(stroke
				(width 0.1)
				(type default)
			)
			(layer "F.Fab")
		)
		(fp_line
			(start -0.12065 0.3048)
			(end -0.67945 0.3048)
			(stroke
				(width 0.1)
				(type default)
			)
			(layer "F.Fab")
		)
		(fp_line
			(start -0.67945 0.3048)
			(end -0.67945 -0.305054)
			(stroke
				(width 0.1)
				(type default)
			)
			(layer "F.Fab")
		)
		(pad "1" smd circle
			(at -0.40005 0 90)
			(size 0 0)
			(layers "F.Cu" "F.Mask" "F.Paste")
			(net "P3V3_OCP_SFF_R")
		)
		(pad "2" smd circle
			(at 0.40005 0 90)
			(size 0 0)
			(layers "F.Cu" "F.Mask" "F.Paste")
			(net "GND")
		)
	)
	(footprint ""
		(layer "F.Cu")
		(at 166.992554 -402.371052 -90)
		(property "Reference" "C772"
			(at 0 0 270)
			(layer "F.SilkS")
			(hide yes)
			(effects
				(font
					(size 1.27 1.27)
				)
			)
		)
		(property "Value" ""
			(at 0 0 270)
			(layer "F.Fab")
			(effects
				(font
					(size 1.27 1.27)
				)
			)
		)
		(duplicate_pad_numbers_are_jumpers no)
		(fp_line
			(start -0.299974 0.150114)
			(end -0.299974 -0.150114)
			(stroke
				(width 0.1)
				(type default)
			)
			(layer "F.Fab")
		)
		(fp_line
			(start 0.299974 0.150114)
			(end -0.299974 0.150114)
			(stroke
				(width 0.1)
				(type default)
			)
			(layer "F.Fab")
		)
		(fp_line
			(start -0.299974 -0.150114)
			(end 0.299974 -0.150114)
			(stroke
				(width 0.1)
				(type default)
			)
			(layer "F.Fab")
		)
		(fp_line
			(start 0.299974 -0.150114)
			(end 0.299974 0.150114)
			(stroke
				(width 0.1)
				(type default)
			)
			(layer "F.Fab")
		)
		(pad "1" smd rect
			(at -0.2667 0 270)
			(size 0.3048 0.381)
			(layers "F.Cu" "F.Mask" "F.Paste")
			(net "P5E_CPU1_PE2_TX_C_DN<0>")
		)
		(pad "2" smd rect
			(at 0.2667 0 270)
			(size 0.3048 0.381)
			(layers "F.Cu" "F.Mask" "F.Paste")
			(net "P5E_CPU1_PE2_TX_DN<0>")
		)
	)
	(footprint ""
		(layer "F.Cu")
		(at 41.874694 -17.623536 90)
		(property "Reference" "C825"
			(at 0 0 90)
			(layer "F.SilkS")
			(hide yes)
			(effects
				(font
					(size 1.27 1.27)
				)
			)
		)
		(property "Value" ""
			(at 0 0 90)
			(layer "F.Fab")
			(effects
				(font
					(size 1.27 1.27)
				)
			)
		)
		(duplicate_pad_numbers_are_jumpers no)
		(fp_line
			(start 0.299974 -0.150114)
			(end 0.299974 0.150114)
			(stroke
				(width 0.1)
				(type default)
			)
			(layer "F.Fab")
		)
		(fp_line
			(start -0.299974 -0.150114)
			(end 0.299974 -0.150114)
			(stroke
				(width 0.1)
				(type default)
			)
			(layer "F.Fab")
		)
		(fp_line
			(start 0.299974 0.150114)
			(end -0.299974 0.150114)
			(stroke
				(width 0.1)
				(type default)
			)
			(layer "F.Fab")
		)
		(fp_line
			(start -0.299974 0.150114)
			(end -0.299974 -0.150114)
			(stroke
				(width 0.1)
				(type default)
			)
			(layer "F.Fab")
		)
		(pad "1" smd rect
			(at -0.2667 0 90)
			(size 0.3048 0.381)
			(layers "F.Cu" "F.Mask" "F.Paste")
			(net "P5E_CPU1_PE1_TX_C_DP<6>")
		)
		(pad "2" smd rect
			(at 0.2667 0 90)
			(size 0.3048 0.381)
			(layers "F.Cu" "F.Mask" "F.Paste")
			(net "P5E_CPU1_PE1_TX_DP<6>")
		)
	)
	(footprint ""
		(layer "F.Cu")
		(at 87.776558 -402.371052 -90)
		(property "Reference" "C736"
			(at 0 0 270)
			(layer "F.SilkS")
			(hide yes)
			(effects
				(font
					(size 1.27 1.27)
				)
			)
		)
		(property "Value" ""
			(at 0 0 270)
			(layer "F.Fab")
			(effects
				(font
					(size 1.27 1.27)
				)
			)
		)
		(duplicate_pad_numbers_are_jumpers no)
		(fp_line
			(start -0.299974 0.150114)
			(end -0.299974 -0.150114)
			(stroke
				(width 0.1)
				(type default)
			)
			(layer "F.Fab")
		)
		(fp_line
			(start 0.299974 0.150114)
			(end -0.299974 0.150114)
			(stroke
				(width 0.1)
				(type default)
			)
			(layer "F.Fab")
		)
		(fp_line
			(start -0.299974 -0.150114)
			(end 0.299974 -0.150114)
			(stroke
				(width 0.1)
				(type default)
			)
			(layer "F.Fab")
		)
		(fp_line
			(start 0.299974 -0.150114)
			(end 0.299974 0.150114)
			(stroke
				(width 0.1)
				(type default)
			)
			(layer "F.Fab")
		)
		(pad "1" smd rect
			(at -0.2667 0 270)
			(size 0.3048 0.381)
			(layers "F.Cu" "F.Mask" "F.Paste")
			(net "P5E_CPU1_PE0_TX_C_DN<2>")
		)
		(pad "2" smd rect
			(at 0.2667 0 270)
			(size 0.3048 0.381)
			(layers "F.Cu" "F.Mask" "F.Paste")
			(net "P5E_CPU1_PE0_TX_DN<2>")
		)
	)
	(footprint ""
		(layer "F.Cu")
		(at 76.53401 -24.713946 -90)
		(property "Reference" "PC2139"
			(at 0 0 270)
			(layer "F.SilkS")
			(hide yes)
			(effects
				(font
					(size 1.27 1.27)
				)
			)
		)
		(property "Value" ""
			(at 0 0 270)
			(layer "F.Fab")
			(effects
				(font
					(size 1.27 1.27)
				)
			)
		)
		(duplicate_pad_numbers_are_jumpers no)
		(fp_line
			(start -0.7874 0.4064)
			(end -0.7874 -0.4064)
			(stroke
				(width 0.1524)
				(type default)
			)
			(layer "F.SilkS")
		)
		(fp_line
			(start 0.7874 0.4064)
			(end -0.7874 0.4064)
			(stroke
				(width 0.1524)
				(type default)
			)
			(layer "F.SilkS")
		)
		(fp_line
			(start -0.7874 -0.4064)
			(end 0.7874 -0.4064)
			(stroke
				(width 0.1524)
				(type default)
			)
			(layer "F.SilkS")
		)
		(fp_line
			(start 0.7874 -0.4064)
			(end 0.7874 0.4064)
			(stroke
				(width 0.1524)
				(type default)
			)
			(layer "F.SilkS")
		)
		(fp_line
			(start -0.67945 0.3048)
			(end -0.67945 -0.305054)
			(stroke
				(width 0.1)
				(type default)
			)
			(layer "F.Fab")
		)
		(fp_line
			(start -0.12065 0.3048)
			(end -0.67945 0.3048)
			(stroke
				(width 0.1)
				(type default)
			)
			(layer "F.Fab")
		)
		(fp_line
			(start 0.120396 0.3048)
			(end 0.120396 0.2794)
			(stroke
				(width 0.1)
				(type default)
			)
			(layer "F.Fab")
		)
		(fp_line
			(start 0.67945 0.3048)
			(end 0.120396 0.3048)
			(stroke
				(width 0.1)
				(type default)
			)
			(layer "F.Fab")
		)
		(fp_line
			(start -0.12065 0.2794)
			(end -0.12065 0.3048)
			(stroke
				(width 0.1)
				(type default)
			)
			(layer "F.Fab")
		)
		(fp_line
			(start 0.120396 0.2794)
			(end -0.12065 0.2794)
			(stroke
				(width 0.1)
				(type default)
			)
			(layer "F.Fab")
		)
		(fp_line
			(start -0.12065 -0.2794)
			(end 0.12065 -0.2794)
			(stroke
				(width 0.1)
				(type default)
			)
			(layer "F.Fab")
		)
		(fp_line
			(start 0.12065 -0.2794)
			(end 0.12065 -0.3048)
			(stroke
				(width 0.1)
				(type default)
			)
			(layer "F.Fab")
		)
		(fp_line
			(start 0.12065 -0.3048)
			(end 0.67945 -0.3048)
			(stroke
				(width 0.1)
				(type default)
			)
			(layer "F.Fab")
		)
		(fp_line
			(start 0.67945 -0.3048)
			(end 0.67945 0.3048)
			(stroke
				(width 0.1)
				(type default)
			)
			(layer "F.Fab")
		)
		(fp_line
			(start -0.67945 -0.305054)
			(end -0.12065 -0.305054)
			(stroke
				(width 0.1)
				(type default)
			)
			(layer "F.Fab")
		)
		(fp_line
			(start -0.12065 -0.305054)
			(end -0.12065 -0.2794)
			(stroke
				(width 0.1)
				(type default)
			)
			(layer "F.Fab")
		)
		(pad "1" smd circle
			(at -0.40005 0 270)
			(size 0 0)
			(layers "F.Cu" "F.Mask" "F.Paste")
			(net "P12V_AUX")
		)
		(pad "2" smd circle
			(at 0.40005 0 270)
			(size 0 0)
			(layers "F.Cu" "F.Mask" "F.Paste")
			(net "GND")
		)
	)
	(footprint ""
		(layer "F.Cu")
		(at 337.792314 -24.212042 -90)
		(property "Reference" "R1253"
			(at 0 0 270)
			(layer "F.SilkS")
			(hide yes)
			(effects
				(font
					(size 1.27 1.27)
				)
			)
		)
		(property "Value" ""
			(at 0 0 270)
			(layer "F.Fab")
			(effects
				(font
					(size 1.27 1.27)
				)
			)
		)
		(duplicate_pad_numbers_are_jumpers no)
		(fp_line
			(start -0.7874 0.4064)
			(end -0.7874 -0.4064)
			(stroke
				(width 0.1524)
				(type default)
			)
			(layer "F.SilkS")
		)
		(fp_line
			(start 0.7874 0.4064)
			(end -0.7874 0.4064)
			(stroke
				(width 0.1524)
				(type default)
			)
			(layer "F.SilkS")
		)
		(fp_line
			(start -0.7874 -0.4064)
			(end 0.7874 -0.4064)
			(stroke
				(width 0.1524)
				(type default)
			)
			(layer "F.SilkS")
		)
		(fp_line
			(start 0.7874 -0.4064)
			(end 0.7874 0.4064)
			(stroke
				(width 0.1524)
				(type default)
			)
			(layer "F.SilkS")
		)
		(fp_line
			(start -0.67945 0.3048)
			(end -0.67945 -0.305054)
			(stroke
				(width 0.1)
				(type default)
			)
			(layer "F.Fab")
		)
		(fp_line
			(start -0.12065 0.3048)
			(end -0.67945 0.3048)
			(stroke
				(width 0.1)
				(type default)
			)
			(layer "F.Fab")
		)
		(fp_line
			(start 0.120396 0.3048)
			(end 0.120396 0.2794)
			(stroke
				(width 0.1)
				(type default)
			)
			(layer "F.Fab")
		)
		(fp_line
			(start 0.67945 0.3048)
			(end 0.120396 0.3048)
			(stroke
				(width 0.1)
				(type default)
			)
			(layer "F.Fab")
		)
		(fp_line
			(start -0.12065 0.2794)
			(end -0.12065 0.3048)
			(stroke
				(width 0.1)
				(type default)
			)
			(layer "F.Fab")
		)
		(fp_line
			(start 0.120396 0.2794)
			(end -0.12065 0.2794)
			(stroke
				(width 0.1)
				(type default)
			)
			(layer "F.Fab")
		)
		(fp_line
			(start -0.12065 -0.2794)
			(end 0.12065 -0.2794)
			(stroke
				(width 0.1)
				(type default)
			)
			(layer "F.Fab")
		)
		(fp_line
			(start 0.12065 -0.2794)
			(end 0.12065 -0.3048)
			(stroke
				(width 0.1)
				(type default)
			)
			(layer "F.Fab")
		)
		(fp_line
			(start 0.12065 -0.3048)
			(end 0.67945 -0.3048)
			(stroke
				(width 0.1)
				(type default)
			)
			(layer "F.Fab")
		)
		(fp_line
			(start 0.67945 -0.3048)
			(end 0.67945 0.3048)
			(stroke
				(width 0.1)
				(type default)
			)
			(layer "F.Fab")
		)
		(fp_line
			(start -0.67945 -0.305054)
			(end -0.12065 -0.305054)
			(stroke
				(width 0.1)
				(type default)
			)
			(layer "F.Fab")
		)
		(fp_line
			(start -0.12065 -0.305054)
			(end -0.12065 -0.2794)
			(stroke
				(width 0.1)
				(type default)
			)
			(layer "F.Fab")
		)
		(pad "1" smd circle
			(at -0.40005 0 270)
			(size 0 0)
			(layers "F.Cu" "F.Mask" "F.Paste")
			(net "PGPPA_AUX")
		)
		(pad "2" smd circle
			(at 0.40005 0 270)
			(size 0 0)
			(layers "F.Cu" "F.Mask" "F.Paste")
			(net "IRQ_LPC_PIRQA_N_ESPI_ALERT0_N")
		)
	)
	(footprint ""
		(layer "F.Cu")
		(at 149.044914 -408.517344 -90)
		(property "Reference" "C1534"
			(at 0 0 270)
			(layer "F.SilkS")
			(hide yes)
			(effects
				(font
					(size 1.27 1.27)
				)
			)
		)
		(property "Value" ""
			(at 0 0 270)
			(layer "F.Fab")
			(effects
				(font
					(size 1.27 1.27)
				)
			)
		)
		(duplicate_pad_numbers_are_jumpers no)
		(fp_line
			(start -0.299974 0.150114)
			(end -0.299974 -0.150114)
			(stroke
				(width 0.1)
				(type default)
			)
			(layer "F.Fab")
		)
		(fp_line
			(start 0.299974 0.150114)
			(end -0.299974 0.150114)
			(stroke
				(width 0.1)
				(type default)
			)
			(layer "F.Fab")
		)
		(fp_line
			(start -0.299974 -0.150114)
			(end 0.299974 -0.150114)
			(stroke
				(width 0.1)
				(type default)
			)
			(layer "F.Fab")
		)
		(fp_line
			(start 0.299974 -0.150114)
			(end 0.299974 0.150114)
			(stroke
				(width 0.1)
				(type default)
			)
			(layer "F.Fab")
		)
		(pad "1" smd rect
			(at -0.2667 0 270)
			(size 0.3048 0.381)
			(layers "F.Cu" "F.Mask" "F.Paste")
			(net "P5E_CPU1_PE3_TX_C_DN<6>")
		)
		(pad "2" smd rect
			(at 0.2667 0 270)
			(size 0.3048 0.381)
			(layers "F.Cu" "F.Mask" "F.Paste")
			(net "P5E_CPU1_PE3_TX_DN<6>")
		)
	)
)
